(kicad_pcb
	(version 20240108)
	(generator "pcbnew")
	(generator_version "8.0")
	(general
		(thickness 1.62)
		(legacy_teardrops no)
	)
	(paper "A4")
	(title_block
		(title "Jetson Orin Baseboard")
		(date "2025-03-12")
		(rev "1.3.4")
		(company "Antmicro Ltd")
		(comment 1 "www.antmicro.com")
		(comment 9 "footprints 476-479 of 677")
	)
	(layers
		(0 "F.Cu" signal)
		(1 "In1.Cu" signal)
		(2 "In2.Cu" signal)
		(3 "In3.Cu" signal)
		(4 "In4.Cu" jumper)
		(5 "In5.Cu" signal)
		(6 "In6.Cu" signal)
		(31 "B.Cu" signal)
		(32 "B.Adhes" user "B.Adhesive")
		(33 "F.Adhes" user "F.Adhesive")
		(34 "B.Paste" user)
		(35 "F.Paste" user)
		(36 "B.SilkS" user "B.Silkscreen")
		(37 "F.SilkS" user "F.Silkscreen")
		(38 "B.Mask" user)
		(39 "F.Mask" user)
		(40 "Dwgs.User" user "User.Drawings")
		(41 "Cmts.User" user "User.Comments")
		(42 "Eco1.User" user "User.Eco1")
		(43 "Eco2.User" user "User.Eco2")
		(44 "Edge.Cuts" user)
		(45 "Margin" user)
		(46 "B.CrtYd" user "B.Courtyard")
		(47 "F.CrtYd" user "F.Courtyard")
		(48 "B.Fab" user)
		(49 "F.Fab" user)
	)
	(footprint "antmicro-footprints:Conn_JST_SH_1x4_SM04B-SRSS-TB-LF-SN"
		(layer "B.Cu")
		(at 131.65 125.651 180)
		(property "Reference" "J14"
			(at 1.9 2.301 0)
			(layer "B.SilkS")
			(effects
				(font
					(size 0.7 0.7)
					(thickness 0.15)
				)
				(justify left bottom mirror)
			)
		)
		(property "Value" "JST_SH_1x4_SM04B-SRSS-TB-LF-SN"
			(at 0 -3.9 0)
			(layer "B.Fab")
			(effects
				(font
					(size 0.7 0.7)
					(thickness 0.15)
				)
				(justify left bottom mirror)
			)
		)
		(property "Footprint" "antmicro-footprints:Conn_JST_SH_1x4_SM04B-SRSS-TB-LF-SN"
			(at 0 0 180)
			(layer "F.Fab")
			(hide yes)
			(effects
				(font
					(size 1.27 1.27)
					(thickness 0.15)
				)
			)
		)
		(property "Datasheet" "https://www.jst-mfg.com/product/pdf/eng/eSH.pdf"
			(at 0 0 180)
			(layer "F.Fab")
			(hide yes)
			(effects
				(font
					(size 1.27 1.27)
					(thickness 0.15)
				)
			)
		)
		(property "Author" "Antmicro"
			(at 263.3 251.302 0)
			(layer "B.Fab")
			(hide yes)
			(effects
				(font
					(size 1 1)
					(thickness 0.15)
				)
				(justify mirror)
			)
		)
		(property "License" "Apache-2.0"
			(at 263.3 251.302 0)
			(layer "B.Fab")
			(hide yes)
			(effects
				(font
					(size 1 1)
					(thickness 0.15)
				)
				(justify mirror)
			)
		)
		(property "MPN" "SM04B-SRSS-TB(LF)(SN)"
			(at 263.3 251.302 0)
			(layer "B.Fab")
			(hide yes)
			(effects
				(font
					(size 1 1)
					(thickness 0.15)
				)
				(justify mirror)
			)
		)
		(property "Manufacturer" "JST Automotive Connectors"
			(at 263.3 251.302 0)
			(layer "B.Fab")
			(hide yes)
			(effects
				(font
					(size 1 1)
					(thickness 0.15)
				)
				(justify mirror)
			)
		)
		(sheetname "Peripherals")
		(sheetfile "peripherals.kicad_sch")
		(attr smd)
		(fp_line
			(start 3.2 2)
			(end 2 2)
			(stroke
				(width 0.15)
				(type solid)
			)
			(layer "B.SilkS")
		)
		(fp_line
			(start 3.2 -0.6)
			(end 3.2 2)
			(stroke
				(width 0.15)
				(type solid)
			)
			(layer "B.SilkS")
		)
		(fp_line
			(start 2 -2.6)
			(end -2 -2.6)
			(stroke
				(width 0.15)
				(type solid)
			)
			(layer "B.SilkS")
		)
		(fp_line
			(start -3.2 2)
			(end -2 2)
			(stroke
				(width 0.15)
				(type solid)
			)
			(layer "B.SilkS")
		)
		(fp_line
			(start -3.2 -0.6)
			(end -3.2 2)
			(stroke
				(width 0.15)
				(type solid)
			)
			(layer "B.SilkS")
		)
		(fp_circle
			(center -2.1 2.5)
			(end -2.05 2.5)
			(stroke
				(width 0.15)
				(type solid)
			)
			(fill solid)
			(layer "B.SilkS")
		)
		(fp_rect
			(start -3.65 3.14)
			(end 3.65 -2.9)
			(stroke
				(width 0.05)
				(type solid)
			)
			(fill none)
			(layer "B.CrtYd")
		)
		(fp_rect
			(start -3 2.475)
			(end 3 -2.475)
			(stroke
				(width 0.15)
				(type solid)
			)
			(fill none)
			(layer "B.Fab")
		)
		(fp_text user "Author: Antmicro"
			(at -4 -6.945 0)
			(layer "B.Fab")
			(hide yes)
			(effects
				(font
					(size 0.7 0.7)
					(thickness 0.15)
				)
				(justify left bottom mirror)
			)
		)
		(fp_text user "${REFERENCE}"
			(at -4 -5.743 0)
			(layer "B.Fab")
			(hide yes)
			(effects
				(font
					(size 0.7 0.7)
					(thickness 0.15)
				)
				(justify left bottom mirror)
			)
		)
		(fp_text user "License: Apache-2.0"
			(at -4 -8.143 0)
			(layer "B.Fab")
			(hide yes)
			(effects
				(font
					(size 0.7 0.7)
					(thickness 0.15)
				)
				(justify left bottom mirror)
			)
		)
		(pad "1" smd roundrect
			(at -1.5 2.12)
			(size 0.6 1.55)
			(layers "B.Cu" "B.Paste" "B.Mask")
			(roundrect_rratio 0.25)
			(net 1 "GND")
			(pintype "passive")
		)
		(pad "2" smd roundrect
			(at -0.5 2.12)
			(size 0.6 1.55)
			(layers "B.Cu" "B.Paste" "B.Mask")
			(roundrect_rratio 0.25)
			(net 662 "/Peripherals/I2C_CONN_3V3")
			(pintype "passive")
		)
		(pad "3" smd roundrect
			(at 0.5 2.12)
			(size 0.6 1.55)
			(layers "B.Cu" "B.Paste" "B.Mask")
			(roundrect_rratio 0.25)
			(net 660 "I2C1_SDA")
			(pintype "passive")
		)
		(pad "4" smd roundrect
			(at 1.5 2.12)
			(size 0.6 1.55)
			(layers "B.Cu" "B.Paste" "B.Mask")
			(roundrect_rratio 0.25)
			(net 659 "I2C1_SCL")
			(pintype "passive")
		)
		(pad "MP" smd roundrect
			(at -2.8 -1.755 180)
			(size 1.2 1.8)
			(layers "B.Cu" "B.Paste" "B.Mask")
			(roundrect_rratio 0.25)
			(net 1 "GND")
			(pintype "passive")
		)
		(pad "MP" smd roundrect
			(at 2.8 -1.755 180)
			(size 1.2 1.8)
			(layers "B.Cu" "B.Paste" "B.Mask")
			(roundrect_rratio 0.25)
			(net 1 "GND")
			(pintype "passive")
		)
	)
	(footprint "antmicro-footprints:SOT-363"
		(layer "B.Cu")
		(at 43.7 74.675)
		(property "Reference" "Q14"
			(at -1.46 1.05 90)
			(layer "B.SilkS")
			(effects
				(font
					(size 0.7 0.7)
					(thickness 0.15)
				)
				(justify right bottom mirror)
			)
		)
		(property "Value" "BCM857BS-7-F"
			(at 0 -2.2 0)
			(layer "B.Fab")
			(effects
				(font
					(size 0.7 0.7)
					(thickness 0.15)
				)
				(justify right bottom mirror)
			)
		)
		(property "Footprint" "antmicro-footprints:SOT-363"
			(at 0 0 0)
			(layer "F.Fab")
			(hide yes)
			(effects
				(font
					(size 1.27 1.27)
					(thickness 0.15)
				)
			)
		)
		(property "Datasheet" "https://www.diodes.com/assets/Datasheets/BCM857BS.pdf"
			(at 0 0 0)
			(layer "F.Fab")
			(hide yes)
			(effects
				(font
					(size 1.27 1.27)
					(thickness 0.15)
				)
			)
		)
		(property "Author" "Antmicro"
			(at 0 0 0)
			(layer "B.Fab")
			(hide yes)
			(effects
				(font
					(size 1 1)
					(thickness 0.15)
				)
				(justify mirror)
			)
		)
		(property "License" "Apache-2.0"
			(at 0 0 0)
			(layer "B.Fab")
			(hide yes)
			(effects
				(font
					(size 1 1)
					(thickness 0.15)
				)
				(justify mirror)
			)
		)
		(property "MPN" "BCM857BS-7-F"
			(at 0 0 0)
			(layer "B.Fab")
			(hide yes)
			(effects
				(font
					(size 1 1)
					(thickness 0.15)
				)
				(justify mirror)
			)
		)
		(property "Manufacturer" "Diodes Incorporated"
			(at 0 0 0)
			(layer "B.Fab")
			(hide yes)
			(effects
				(font
					(size 1 1)
					(thickness 0.15)
				)
				(justify mirror)
			)
		)
		(sheetname "Supply")
		(sheetfile "supply.kicad_sch")
		(attr smd)
		(fp_line
			(start -0.8 -1.223)
			(end -0.8 -1.146)
			(stroke
				(width 0.15)
				(type solid)
			)
			(layer "B.SilkS")
		)
		(fp_line
			(start -0.72 1.228)
			(end -0.72 1.153)
			(stroke
				(width 0.15)
				(type solid)
			)
			(layer "B.SilkS")
		)
		(fp_line
			(start -0.72 1.228)
			(end 0.803 1.228)
			(stroke
				(width 0.15)
				(type solid)
			)
			(layer "B.SilkS")
		)
		(fp_line
			(start 0.803 -1.223)
			(end -0.8 -1.223)
			(stroke
				(width 0.15)
				(type solid)
			)
			(layer "B.SilkS")
		)
		(fp_line
			(start 0.803 -1.223)
			(end 0.803 -1.146)
			(stroke
				(width 0.15)
				(type solid)
			)
			(layer "B.SilkS")
		)
		(fp_line
			(start 0.803 1.228)
			(end 0.803 1.153)
			(stroke
				(width 0.15)
				(type solid)
			)
			(layer "B.SilkS")
		)
		(fp_circle
			(center -0.978102 1.2)
			(end -0.928102 1.2)
			(stroke
				(width 0.15)
				(type solid)
			)
			(fill solid)
			(layer "B.SilkS")
		)
		(fp_rect
			(start 1.3 1.3)
			(end -1.3 -1.3)
			(stroke
				(width 0.05)
				(type solid)
			)
			(fill none)
			(layer "B.CrtYd")
		)
		(fp_line
			(start -0.68 0.52)
			(end -0.1 1.1)
			(stroke
				(width 0.15)
				(type solid)
			)
			(layer "B.Fab")
		)
		(fp_rect
			(start 0.68 -1.1)
			(end -0.68 1.1)
			(stroke
				(width 0.15)
				(type solid)
			)
			(fill none)
			(layer "B.Fab")
		)
		(fp_text user "License: Apache-2.0"
			(at -1.3 -5.2 0)
			(layer "B.Fab")
			(hide yes)
			(effects
				(font
					(size 0.7 0.7)
					(thickness 0.15)
				)
				(justify right bottom mirror)
			)
		)
		(fp_text user "Author: Antmicro"
			(at -1.3 -6.4 0)
			(layer "B.Fab")
			(hide yes)
			(effects
				(font
					(size 0.7 0.7)
					(thickness 0.15)
				)
				(justify right bottom mirror)
			)
		)
		(fp_text user "${REFERENCE}"
			(at -1.3 -4 0)
			(layer "B.Fab")
			(hide yes)
			(effects
				(font
					(size 0.7 0.7)
					(thickness 0.15)
				)
				(justify right bottom mirror)
			)
		)
		(pad "1" smd custom
			(at -0.948 0.752 90)
			(size 0.6 0.6)
			(layers "B.Cu" "B.Paste" "B.Mask")
			(net 328 "/Supply/VCC_IN")
			(pintype "passive")
			(options
				(clearance outline)
				(anchor rect)
			)
			(primitives)
		)
		(pad "2" smd rect
			(at -0.948 0.002 90)
			(size 0.4 0.6)
			(layers "B.Cu" "B.Paste" "B.Mask")
			(net 718 "Net-(Q14-Pad2)")
			(pintype "passive")
		)
		(pad "3" smd custom
			(at -0.948 -0.745 90)
			(size 0.6 0.6)
			(layers "B.Cu" "B.Paste" "B.Mask")
			(net 718 "Net-(Q14-Pad2)")
			(pintype "passive")
			(options
				(clearance outline)
				(anchor rect)
			)
			(primitives)
		)
		(pad "4" smd custom
			(at 0.951 -0.745 90)
			(size 0.6 0.6)
			(layers "B.Cu" "B.Paste" "B.Mask")
			(net 500 "POE_OUTPUT")
			(pintype "passive")
			(options
				(clearance outline)
				(anchor rect)
			)
			(primitives)
		)
		(pad "5" smd rect
			(at 0.951 0.002 90)
			(size 0.4 0.6)
			(layers "B.Cu" "B.Paste" "B.Mask")
			(net 718 "Net-(Q14-Pad2)")
			(pintype "passive")
		)
		(pad "6" smd custom
			(at 0.951 0.752 90)
			(size 0.6 0.6)
			(layers "B.Cu" "B.Paste" "B.Mask")
			(net 631 "Net-(Q16-G)")
			(pintype "passive")
			(options
				(clearance outline)
				(anchor rect)
			)
			(primitives)
		)
	)
	(footprint "antmicro-footprints:XSON-8_1x1.95mm_P0.5mm"
		(layer "B.Cu")
		(at 66.8 79.99 90)
		(property "Reference" "U4"
			(at 1.56 -1.3 -90)
			(layer "B.SilkS")
			(effects
				(font
					(size 0.7 0.7)
					(thickness 0.15)
				)
				(justify left bottom mirror)
			)
		)
		(property "Value" "NTS0102_XSON"
			(at 0 -2.2 -90)
			(layer "B.Fab")
			(effects
				(font
					(size 0.7 0.7)
					(thickness 0.15)
				)
				(justify left bottom mirror)
			)
		)
		(property "Footprint" "antmicro-footprints:XSON-8_1x1.95mm_P0.5mm"
			(at 0 0 90)
			(layer "F.Fab")
			(hide yes)
			(effects
				(font
					(size 1.27 1.27)
					(thickness 0.15)
				)
			)
		)
		(property "Datasheet" "http://www.farnell.com/datasheets/1760723.pdf"
			(at 0 0 90)
			(layer "F.Fab")
			(hide yes)
			(effects
				(font
					(size 1.27 1.27)
					(thickness 0.15)
				)
			)
		)
		(property "Author" "Antmicro"
			(at 146.79 13.19 0)
			(layer "B.Fab")
			(hide yes)
			(effects
				(font
					(size 1 1)
					(thickness 0.15)
				)
				(justify mirror)
			)
		)
		(property "License" "Apache-2.0"
			(at 146.79 13.19 0)
			(layer "B.Fab")
			(hide yes)
			(effects
				(font
					(size 1 1)
					(thickness 0.15)
				)
				(justify mirror)
			)
		)
		(property "MPN" "NTS0102GT"
			(at 146.79 13.19 0)
			(layer "B.Fab")
			(hide yes)
			(effects
				(font
					(size 1 1)
					(thickness 0.15)
				)
				(justify mirror)
			)
		)
		(property "Manufacturer" "NXP"
			(at 146.79 13.19 0)
			(layer "B.Fab")
			(hide yes)
			(effects
				(font
					(size 1 1)
					(thickness 0.15)
				)
				(justify mirror)
			)
		)
		(sheetname "SoM")
		(sheetfile "som.kicad_sch")
		(attr smd)
		(fp_line
			(start -0.5 -1.1)
			(end 0.5 -1.1)
			(stroke
				(width 0.15)
				(type solid)
			)
			(layer "B.SilkS")
		)
		(fp_line
			(start 0.5 1.1)
			(end -0.5 1.1)
			(stroke
				(width 0.15)
				(type solid)
			)
			(layer "B.SilkS")
		)
		(fp_circle
			(center -0.75 1.1)
			(end -0.701 1.1)
			(stroke
				(width 0.15)
				(type solid)
			)
			(fill none)
			(layer "B.SilkS")
		)
		(fp_rect
			(start -0.8 1.2)
			(end 0.8 -1.2)
			(stroke
				(width 0.05)
				(type solid)
			)
			(fill none)
			(layer "B.CrtYd")
		)
		(fp_line
			(start 0.5305 -1)
			(end 0.5305 1.001)
			(stroke
				(width 0.15)
				(type solid)
			)
			(layer "B.Fab")
		)
		(fp_line
			(start -0.5305 -1)
			(end 0.5305 -1)
			(stroke
				(width 0.15)
				(type solid)
			)
			(layer "B.Fab")
		)
		(fp_line
			(start 0.5305 1.001)
			(end -0.5305 1.001)
			(stroke
				(width 0.15)
				(type solid)
			)
			(layer "B.Fab")
		)
		(fp_line
			(start -0.5305 1.001)
			(end -0.5305 -1)
			(stroke
				(width 0.15)
				(type solid)
			)
			(layer "B.Fab")
		)
		(fp_text user "License: Apache-2.0"
			(at -0.527 -8.306 -90)
			(layer "B.Fab")
			(hide yes)
			(effects
				(font
					(size 0.7 0.7)
					(thickness 0.15)
				)
				(justify left bottom mirror)
			)
		)
		(fp_text user "Author: Antmicro"
			(at -0.527 -7.105 -90)
			(layer "B.Fab")
			(hide yes)
			(effects
				(font
					(size 0.7 0.7)
					(thickness 0.15)
				)
				(justify left bottom mirror)
			)
		)
		(fp_text user "${REFERENCE}"
			(at -0.527 -5.905 -90)
			(layer "B.Fab")
			(hide yes)
			(effects
				(font
					(size 0.7 0.7)
					(thickness 0.15)
				)
				(justify left bottom mirror)
			)
		)
		(pad "1" smd roundrect
			(at -0.45 0.75 270)
			(size 0.6 0.3)
			(layers "B.Cu" "B.Paste" "B.Mask")
			(roundrect_rratio 0.25)
			(net 475 "DEBUG_TXD")
			(pinfunction "B_{2}")
			(pintype "bidirectional")
		)
		(pad "2" smd roundrect
			(at -0.45 0.25 270)
			(size 0.6 0.25)
			(layers "B.Cu" "B.Paste" "B.Mask")
			(roundrect_rratio 0.25)
			(net 1 "GND")
			(pinfunction "GND")
			(pintype "power_in")
		)
		(pad "3" smd roundrect
			(at -0.45 -0.25 270)
			(size 0.6 0.25)
			(layers "B.Cu" "B.Paste" "B.Mask")
			(roundrect_rratio 0.25)
			(net 112 "+1V8")
			(pinfunction "VCC_{A}")
			(pintype "power_in")
		)
		(pad "4" smd roundrect
			(at -0.45 -0.75 270)
			(size 0.6 0.3)
			(layers "B.Cu" "B.Paste" "B.Mask")
			(roundrect_rratio 0.25)
			(net 168 "/SoM/DEBUG_TXD_1V8")
			(pinfunction "A_{2}")
			(pintype "bidirectional")
		)
		(pad "5" smd roundrect
			(at 0.45 -0.75 270)
			(size 0.6 0.3)
			(layers "B.Cu" "B.Paste" "B.Mask")
			(roundrect_rratio 0.25)
			(net 327 "/SoM/DEBUG_RXD_1V8")
			(pinfunction "A_{1}")
			(pintype "bidirectional")
		)
		(pad "6" smd roundrect
			(at 0.45 -0.25 270)
			(size 0.6 0.25)
			(layers "B.Cu" "B.Paste" "B.Mask")
			(roundrect_rratio 0.25)
			(net 112 "+1V8")
			(pinfunction "OE")
			(pintype "input")
		)
		(pad "7" smd roundrect
			(at 0.45 0.25 270)
			(size 0.6 0.25)
			(layers "B.Cu" "B.Paste" "B.Mask")
			(roundrect_rratio 0.25)
			(net 87 "+3V3")
			(pinfunction "VCC_{B}")
			(pintype "power_in")
		)
		(pad "8" smd roundrect
			(at 0.45 0.75 270)
			(size 0.6 0.3)
			(layers "B.Cu" "B.Paste" "B.Mask")
			(roundrect_rratio 0.25)
			(net 477 "DEBUG_RXD")
			(pinfunction "B_{1}")
			(pintype "bidirectional")
		)
	)
	(footprint "antmicro-footprints:TP_SMD_0.75mm"
		(layer "B.Cu")
		(at 63.79 97)
		(property "Reference" "TP13"
			(at 1.42 -0.42 180)
			(layer "B.SilkS")
			(hide yes)
			(effects
				(font
					(size 0.7 0.7)
					(thickness 0.15)
				)
				(justify left bottom mirror)
			)
		)
		(property "Value" "TP_0.75mm_SMD"
			(at 0 -1.2 180)
			(layer "B.Fab")
			(effects
				(font
					(size 0.7 0.7)
					(thickness 0.15)
				)
				(justify left bottom mirror)
			)
		)
		(property "Footprint" "antmicro-footprints:TP_SMD_0.75mm"
			(at 0 0 0)
			(layer "F.Fab")
			(hide yes)
			(effects
				(font
					(size 1.27 1.27)
					(thickness 0.15)
				)
			)
		)
		(property "Author" "Antmicro"
			(at 0 0 0)
			(layer "B.Fab")
			(hide yes)
			(effects
				(font
					(size 1 1)
					(thickness 0.15)
				)
				(justify mirror)
			)
		)
		(property "License" "Apache-2.0"
			(at 0 0 0)
			(layer "B.Fab")
			(hide yes)
			(effects
				(font
					(size 1 1)
					(thickness 0.15)
				)
				(justify mirror)
			)
		)
		(property "MPN" ""
			(at 0 0 0)
			(layer "B.Fab")
			(hide yes)
			(effects
				(font
					(size 1 1)
					(thickness 0.15)
				)
				(justify mirror)
			)
		)
		(property "Manufacturer" ""
			(at 0 0 0)
			(layer "B.Fab")
			(hide yes)
			(effects
				(font
					(size 1 1)
					(thickness 0.15)
				)
				(justify mirror)
			)
		)
		(sheetname "USB Debug, DP")
		(sheetfile "usb.kicad_sch")
		(attr exclude_from_pos_files exclude_from_bom)
		(fp_circle
			(center 0 0)
			(end 0.475 0)
			(stroke
				(width 0.05)
				(type default)
			)
			(fill none)
			(layer "B.CrtYd")
		)
		(fp_text user "${REFERENCE}"
			(at -0.4 -2.7 180)
			(layer "B.Fab")
			(hide yes)
			(effects
				(font
					(size 0.7 0.7)
					(thickness 0.15)
				)
				(justify left bottom mirror)
			)
		)
		(fp_text user "Author: Antmicro"
			(at -0.4 -3.901 180)
			(layer "B.Fab")
			(hide yes)
			(effects
				(font
					(size 0.7 0.7)
					(thickness 0.15)
				)
				(justify left bottom mirror)
			)
		)
		(fp_text user "License: Apache-2.0"
			(at -0.4 -5.101 180)
			(layer "B.Fab")
			(hide yes)
			(effects
				(font
					(size 0.7 0.7)
					(thickness 0.15)
				)
				(justify left bottom mirror)
			)
		)
		(pad "1" smd circle
			(at 0 0)
			(size 0.75 0.75)
			(layers "B.Cu" "B.Mask")
			(net 691 "Net-(U6A-GPIO3{slash}HPD1)")
			(pinfunction "1")
			(pintype "passive")
		)
	)
)
